# T6G (Grand Teton) — schematic netlist excerpt (pin names and nets, part order shuffled) for the footprints in the layout excerpt that follows; sources: Cadence DE-HDL packaged netlist, KiCad conversion of 04192023_DAF0TMB3IC0_F0TG_MB_C_brd_V02_OCP.brd

R1490  Q_RES  1K 1% EMPTY  pkg 0201LF  page 342 : A = P1V8_CPU1_RT_1D ; B = JTAG_TDO_RT_CPU1_P2
R1419  Q_RES  4.7K 5% CHIP  pkg 0402LF  page 164 : A = PVDD18_S5_P0 ; B = UART_LS_EN_R_N

(kicad_pcb
	(version 20260206)
	(generator "pcbnew")
	(generator_version "10.0")
	(general
		(thickness 1.6)
		(legacy_teardrops no)
	)
	(paper "A4")
	(title_block
		(title "04192023_DAF0TMB3IC0_F0TG_MB_C_brd_V02_OCP.brd")
		(comment 1 "Grand Teton / footprints 3797-3798 of 8354")
	)
	(layers
		(0 "F.Cu" signal "TOP")
		(4 "In1.Cu" signal "GND")
		(6 "In2.Cu" signal "IN1")
		(8 "In3.Cu" signal "GND1")
		(10 "In4.Cu" signal "IN2")
		(12 "In5.Cu" signal "GND2")
		(14 "In6.Cu" signal "IN3")
		(16 "In7.Cu" signal "GND3")
		(18 "In8.Cu" signal "VCC")
		(20 "In9.Cu" signal "VCC1")
		(22 "In10.Cu" signal "GND4")
		(24 "In11.Cu" signal "IN4")
		(26 "In12.Cu" signal "GND5")
		(28 "In13.Cu" signal "IN5")
		(30 "In14.Cu" signal "GND6")
		(32 "In15.Cu" signal "IN6")
		(34 "In16.Cu" signal "GND7")
		(2 "B.Cu" signal "BOTTOM")
		(9 "F.Adhes" user "F.Adhesive")
		(11 "B.Adhes" user "B.Adhesive")
		(13 "F.Paste" user "Package Geometry/Pastemask Top")
		(15 "B.Paste" user "Package Geometry/Pastemask Bottom")
		(5 "F.SilkS" user "Ref Des/Silkscreen Top")
		(7 "B.SilkS" user "Ref Des/Silkscreen Bottom")
		(1 "F.Mask" user "Board Geometry/Soldermask Top")
		(3 "B.Mask" user "Board Geometry/Soldermask Bottom")
		(17 "Dwgs.User" user "User.Drawings")
		(19 "Cmts.User" user "User.Comments")
		(21 "Eco1.User" user "User.Eco1")
		(23 "Eco2.User" user "User.Eco2")
		(25 "Edge.Cuts" user "Board Geometry/Outline")
		(27 "Margin" user)
		(31 "F.CrtYd" user "Package Geometry/Place Bound Top")
		(29 "B.CrtYd" user "Package Geometry/Place Bound Bottom")
		(35 "F.Fab" user "Ref Des/Assembly Top")
		(33 "B.Fab" user "Ref Des/Assembly Bottom")
	)
	(footprint ""
		(layer "F.Cu")
		(at 363.008926 -28.273502 90)
		(property "Reference" "R1419"
			(at 0 0 90)
			(layer "F.SilkS")
			(hide yes)
			(effects
				(font
					(size 1.27 1.27)
				)
			)
		)
		(property "Value" ""
			(at 0 0 90)
			(layer "F.Fab")
			(effects
				(font
					(size 1.27 1.27)
				)
			)
		)
		(duplicate_pad_numbers_are_jumpers no)
		(fp_line
			(start 0.7874 -0.4064)
			(end 0.7874 0.4064)
			(stroke
				(width 0.1524)
				(type default)
			)
			(layer "F.SilkS")
		)
		(fp_line
			(start -0.7874 -0.4064)
			(end 0.7874 -0.4064)
			(stroke
				(width 0.1524)
				(type default)
			)
			(layer "F.SilkS")
		)
		(fp_line
			(start 0.7874 0.4064)
			(end -0.7874 0.4064)
			(stroke
				(width 0.1524)
				(type default)
			)
			(layer "F.SilkS")
		)
		(fp_line
			(start -0.7874 0.4064)
			(end -0.7874 -0.4064)
			(stroke
				(width 0.1524)
				(type default)
			)
			(layer "F.SilkS")
		)
		(fp_line
			(start -0.12065 -0.305054)
			(end -0.12065 -0.2794)
			(stroke
				(width 0.1)
				(type default)
			)
			(layer "F.Fab")
		)
		(fp_line
			(start -0.67945 -0.305054)
			(end -0.12065 -0.305054)
			(stroke
				(width 0.1)
				(type default)
			)
			(layer "F.Fab")
		)
		(fp_line
			(start 0.67945 -0.3048)
			(end 0.67945 0.3048)
			(stroke
				(width 0.1)
				(type default)
			)
			(layer "F.Fab")
		)
		(fp_line
			(start 0.12065 -0.3048)
			(end 0.67945 -0.3048)
			(stroke
				(width 0.1)
				(type default)
			)
			(layer "F.Fab")
		)
		(fp_line
			(start 0.12065 -0.2794)
			(end 0.12065 -0.3048)
			(stroke
				(width 0.1)
				(type default)
			)
			(layer "F.Fab")
		)
		(fp_line
			(start -0.12065 -0.2794)
			(end 0.12065 -0.2794)
			(stroke
				(width 0.1)
				(type default)
			)
			(layer "F.Fab")
		)
		(fp_line
			(start 0.120396 0.2794)
			(end -0.12065 0.2794)
			(stroke
				(width 0.1)
				(type default)
			)
			(layer "F.Fab")
		)
		(fp_line
			(start -0.12065 0.2794)
			(end -0.12065 0.3048)
			(stroke
				(width 0.1)
				(type default)
			)
			(layer "F.Fab")
		)
		(fp_line
			(start 0.67945 0.3048)
			(end 0.120396 0.3048)
			(stroke
				(width 0.1)
				(type default)
			)
			(layer "F.Fab")
		)
		(fp_line
			(start 0.120396 0.3048)
			(end 0.120396 0.2794)
			(stroke
				(width 0.1)
				(type default)
			)
			(layer "F.Fab")
		)
		(fp_line
			(start -0.12065 0.3048)
			(end -0.67945 0.3048)
			(stroke
				(width 0.1)
				(type default)
			)
			(layer "F.Fab")
		)
		(fp_line
			(start -0.67945 0.3048)
			(end -0.67945 -0.305054)
			(stroke
				(width 0.1)
				(type default)
			)
			(layer "F.Fab")
		)
		(pad "1" smd circle
			(at -0.40005 0 90)
			(size 0 0)
			(layers "F.Cu" "F.Mask" "F.Paste")
			(net "PVDD18_S5_P0")
		)
		(pad "2" smd circle
			(at 0.40005 0 90)
			(size 0 0)
			(layers "F.Cu" "F.Mask" "F.Paste")
			(net "UART_LS_EN_R_N")
		)
	)
	(footprint ""
		(layer "F.Cu")
		(at 177.81016 -391.6172)
		(property "Reference" "R1490"
			(at 0 0 0)
			(layer "F.SilkS")
			(hide yes)
			(effects
				(font
					(size 1.27 1.27)
				)
			)
		)
		(property "Value" ""
			(at 0 0 0)
			(layer "F.Fab")
			(effects
				(font
					(size 1.27 1.27)
				)
			)
		)
		(duplicate_pad_numbers_are_jumpers no)
		(fp_line
			(start -0.32512 -0.175006)
			(end 0.32512 -0.175006)
			(stroke
				(width 0.1)
				(type default)
			)
			(layer "F.Fab")
		)
		(fp_line
			(start -0.32512 0.175006)
			(end -0.32512 -0.175006)
			(stroke
				(width 0.1)
				(type default)
			)
			(layer "F.Fab")
		)
		(fp_line
			(start 0.32512 -0.175006)
			(end 0.32512 0.175006)
			(stroke
				(width 0.1)
				(type default)
			)
			(layer "F.Fab")
		)
		(fp_line
			(start 0.32512 0.175006)
			(end -0.32512 0.175006)
			(stroke
				(width 0.1)
				(type default)
			)
			(layer "F.Fab")
		)
		(pad "1" smd rect
			(at -0.2667 0)
			(size 0.3048 0.381)
			(layers "F.Cu" "F.Mask" "F.Paste")
			(net "P1V8_CPU1_RT_1D")
		)
		(pad "2" smd rect
			(at 0.2667 0 180)
			(size 0.3048 0.381)
			(layers "F.Cu" "F.Mask" "F.Paste")
			(net "JTAG_TDO_RT_CPU1_P2")
		)
	)
)
